G04 #@! TF.GenerationSoftware,KiCad,Pcbnew,(5.0.1)-3*
G04 #@! TF.CreationDate,2019-04-10T15:36:06+02:00*
G04 #@! TF.ProjectId,discovery,646973636F766572792E6B696361645F,rev?*
G04 #@! TF.SameCoordinates,PX4c4640PY8a48028*
G04 #@! TF.FileFunction,Other,User*
%FSLAX46Y46*%
G04 Gerber Fmt 4.6, Leading zero omitted, Abs format (unit mm)*
%MOMM*%
%LPD*%
G01*
G04 APERTURE LIST*
%ADD10C,0.100000*%
%ADD11C,0.050000*%
G04 APERTURE END LIST*
D10*
G04 #@! TO.C,J2*
X33451280Y33698440D02*
X33451280Y55498440D01*
X22951280Y33698440D02*
X33451280Y33698440D01*
X22951280Y55498440D02*
X22951280Y33698440D01*
X33451280Y55498440D02*
X22951280Y55498440D01*
G04 #@! TO.C,J4*
X2551280Y33698440D02*
X13051280Y33698440D01*
X13051280Y33698440D02*
X13051280Y55498440D01*
X13051280Y55498440D02*
X2551280Y55498440D01*
X2551280Y55498440D02*
X2551280Y33698440D01*
G04 #@! TO.C,J5*
X2551280Y26665840D02*
X2551280Y4865840D01*
X13051280Y26665840D02*
X2551280Y26665840D01*
X13051280Y4865840D02*
X13051280Y26665840D01*
X2551280Y4865840D02*
X13051280Y4865840D01*
G04 #@! TO.C,J6*
X33451280Y26665840D02*
X22951280Y26665840D01*
X22951280Y26665840D02*
X22951280Y4865840D01*
X22951280Y4865840D02*
X33451280Y4865840D01*
X33451280Y4865840D02*
X33451280Y26665840D01*
G04 #@! TO.C,J1*
X1951280Y85698440D02*
X1951280Y59698440D01*
X13101280Y85698440D02*
X1951280Y85698440D01*
X13101280Y59698440D02*
X13101280Y85698440D01*
X1951280Y59698440D02*
X13101280Y59698440D01*
G04 #@! TO.C,J3*
X34051280Y85698440D02*
X22901280Y85698440D01*
X22901280Y85698440D02*
X22901280Y59698440D01*
X22901280Y59698440D02*
X34051280Y59698440D01*
X34051280Y59698440D02*
X34051280Y85698440D01*
D11*
G04 #@! TO.C,W1*
X143001280Y-1560D02*
G75*
G03X143001280Y-1560I-3000000J0D01*
G01*
G04 #@! TO.C,W2*
X3001280Y89998440D02*
G75*
G03X3001280Y89998440I-3000000J0D01*
G01*
G04 #@! TO.C,W3*
X143001280Y89998440D02*
G75*
G03X143001280Y89998440I-3000000J0D01*
G01*
G04 #@! TO.C,W4*
X3001280Y-1560D02*
G75*
G03X3001280Y-1560I-3000000J0D01*
G01*
D10*
G04 #@! TO.C,W5*
X62601280Y77998440D02*
G75*
G03X62601280Y77998440I-7600000J0D01*
G01*
G04 #@! TO.C,W6*
X62601280Y55498440D02*
G75*
G03X62601280Y55498440I-7600000J0D01*
G01*
G04 #@! TO.C,W7*
X62601280Y32998440D02*
G75*
G03X62601280Y32998440I-7600000J0D01*
G01*
G04 #@! TO.C,W8*
X62601280Y10498440D02*
G75*
G03X62601280Y10498440I-7600000J0D01*
G01*
G04 #@! TO.C,W9*
X122601280Y80748440D02*
G75*
G03X122601280Y80748440I-7600000J0D01*
G01*
G04 #@! TO.C,W10*
X122601280Y58248440D02*
G75*
G03X122601280Y58248440I-7600000J0D01*
G01*
G04 #@! TO.C,W11*
X122601280Y13248440D02*
G75*
G03X122601280Y13248440I-7600000J0D01*
G01*
G04 #@! TO.C,W12*
X122601280Y35748440D02*
G75*
G03X122601280Y35748440I-7600000J0D01*
G01*
G04 #@! TD*
M02*
